# TIMECARD (Time Appliance Project (Time Card)) — schematic netlist excerpt (pin names and nets, part order shuffled) for the footprints in the layout excerpt that follows; sources: Cadence DE-HDL packaged netlist, KiCad conversion of R4006-B0001-02_R01.brd

R396  RESISTOR  33OHM 1%  pkg SMC_0402R_H016  page 26 : \1\ = SMA4_LED_RED_N ; \2\ = UNNAMED_14_LED4PV14_I268_3
R124  RESISTOR  100OHM 1%  pkg SMC_0402R_H016  page 26 : \1\ = FPGA_OUT_SMA1_LED_BLUE_N ; \2\ = UNNAMED_14_LED4PV14_I265_1

(kicad_pcb
	(version 20260206)
	(generator "pcbnew")
	(generator_version "10.0")
	(general
		(thickness 1.6)
		(legacy_teardrops no)
	)
	(paper "A4")
	(title_block
		(title "timecard-production-celestica-r4006 — R4006-B0001-02_R01.brd")
		(comment 1 "Time Appliance Project (Time Card) / footprints 42-43 of 1113")
	)
	(layers
		(0 "F.Cu" signal "TOP")
		(4 "In1.Cu" signal "L02_GND1")
		(6 "In2.Cu" signal "L03_SIG1")
		(8 "In3.Cu" signal "L04_GND2")
		(10 "In4.Cu" signal "L05_VCC1")
		(12 "In5.Cu" signal "L06_VCC2")
		(14 "In6.Cu" signal "L07_GND3")
		(16 "In7.Cu" signal "L08_SIG2")
		(18 "In8.Cu" signal "L09_GND4")
		(2 "B.Cu" signal "BOTTOM")
		(9 "F.Adhes" user "F.Adhesive")
		(11 "B.Adhes" user "B.Adhesive")
		(13 "F.Paste" user "Package Geometry/Pastemask Top")
		(15 "B.Paste" user "Package Geometry/Pastemask Bottom")
		(5 "F.SilkS" user "Ref Des/Silkscreen Top")
		(7 "B.SilkS" user "Ref Des/Silkscreen Bottom")
		(1 "F.Mask" user "Board Geometry/Soldermask Top")
		(3 "B.Mask" user "Board Geometry/Soldermask Bottom")
		(17 "Dwgs.User" user "User.Drawings")
		(19 "Cmts.User" user "User.Comments")
		(21 "Eco1.User" user "User.Eco1")
		(23 "Eco2.User" user "User.Eco2")
		(25 "Edge.Cuts" user "Board Geometry/Outline")
		(27 "Margin" user)
		(31 "F.CrtYd" user "Package Geometry/Place Bound Top")
		(29 "B.CrtYd" user "Package Geometry/Place Bound Bottom")
		(35 "F.Fab" user "Ref Des/Assembly Top")
		(33 "B.Fab" user "Ref Des/Assembly Bottom")
	)
	(footprint ""
		(layer "F.Cu")
		(at 19.468338 -47.879 180)
		(property "Reference" "R396"
			(at -3.518662 -0.03937 0)
			(unlocked yes)
			(layer "F.SilkS")
			(effects
				(font
					(size 0.7874 0.5842)
					(thickness 0.1524)
				)
			)
		)
		(property "Value" "VAL*"
			(at 0.02032 2.13233 180)
			(unlocked yes)
			(layer "F.Fab")
			(hide yes)
			(effects
				(font
					(size 0.7874 0.5842)
					(thickness 0.1524)
				)
			)
		)
		(property "Tolerance" "TOL*"
			(at 0.044704 3.05435 180)
			(unlocked yes)
			(layer "Cmts.User")
			(hide yes)
			(effects
				(font
					(size 0.7874 0.5842)
					(thickness 0.1524)
				)
			)
		)
		(property "User Part Number" "PARTNUM*"
			(at 0.02032 4.024884 180)
			(unlocked yes)
			(layer "Cmts.User")
			(hide yes)
			(effects
				(font
					(size 0.7874 0.5842)
					(thickness 0.1524)
				)
			)
		)
		(property "Device Type" "RESISTOR-G155-133R0-01,33OHM,1%"
			(at 0.008382 1.210564 180)
			(unlocked yes)
			(layer "F.Fab")
			(hide yes)
			(effects
				(font
					(size 0.7874 0.5842)
					(thickness 0.1524)
				)
			)
		)
		(duplicate_pad_numbers_are_jumpers no)
		(fp_line
			(start 1.143 0.5588)
			(end 1.143 -0.5588)
			(stroke
				(width 0.1)
				(type default)
			)
			(layer "F.SilkS")
		)
		(fp_line
			(start 1.143 -0.5588)
			(end -1.143 -0.5588)
			(stroke
				(width 0.1)
				(type default)
			)
			(layer "F.SilkS")
		)
		(fp_line
			(start -1.143 0.5588)
			(end 1.143 0.5588)
			(stroke
				(width 0.1)
				(type default)
			)
			(layer "F.SilkS")
		)
		(fp_line
			(start -1.143 -0.5588)
			(end -1.143 0.5588)
			(stroke
				(width 0.1)
				(type default)
			)
			(layer "F.SilkS")
		)
		(fp_rect
			(start -1.143 -0.5588)
			(end 1.143 0.5588)
			(stroke
				(width 0)
				(type default)
			)
			(fill no)
			(layer "F.CrtYd")
		)
		(fp_line
			(start 0.508 0.3048)
			(end 0.508 -0.3048)
			(stroke
				(width 0.1)
				(type default)
			)
			(layer "F.Fab")
		)
		(fp_line
			(start 0.508 -0.3048)
			(end -0.508 -0.3048)
			(stroke
				(width 0.1)
				(type default)
			)
			(layer "F.Fab")
		)
		(fp_line
			(start -0.508 0.3048)
			(end 0.508 0.3048)
			(stroke
				(width 0.1)
				(type default)
			)
			(layer "F.Fab")
		)
		(fp_line
			(start -0.508 -0.3048)
			(end -0.508 0.3048)
			(stroke
				(width 0.1)
				(type default)
			)
			(layer "F.Fab")
		)
		(pad "1" smd rect
			(at -0.5334 0 180)
			(size 0.7112 0.6096)
			(layers "F.Cu" "F.Mask" "F.Paste")
			(net "SMA4_LED_RED_N")
		)
		(pad "2" smd rect
			(at 0.5334 0 180)
			(size 0.7112 0.6096)
			(layers "F.Cu" "F.Mask" "F.Paste")
			(net "UNNAMED_14_LED4PV14_I268_3")
		)
		(zone
			(layer "F.Cu")
			(hatch none 0.5)
			(connect_pads
				(clearance 0)
			)
			(min_thickness 0.25)
			(keepout
				(tracks not_allowed)
				(vias allowed)
				(pads allowed)
				(copperpour not_allowed)
				(footprints allowed)
			)
			(placement
				(enabled no)
				(sheetname "")
			)
			(fill
				(thermal_gap 0.5)
				(thermal_bridge_width 0.5)
				(island_removal_mode 0)
			)
			(polygon
				(pts
					(xy 19.544538 -47.5742) (xy 19.544538 -48.1838) (xy 19.392138 -48.1838) (xy 19.392138 -47.5742)
				)
			)
		)
		(zone
			(layer "F.Cu")
			(hatch none 0.5)
			(connect_pads
				(clearance 0)
			)
			(min_thickness 0.25)
			(keepout
				(tracks allowed)
				(vias not_allowed)
				(pads allowed)
				(copperpour not_allowed)
				(footprints allowed)
			)
			(placement
				(enabled no)
				(sheetname "")
			)
			(fill
				(thermal_gap 0.5)
				(thermal_bridge_width 0.5)
				(island_removal_mode 0)
			)
			(polygon
				(pts
					(xy 19.544538 -47.5742) (xy 19.544538 -48.1838) (xy 19.392138 -48.1838) (xy 19.392138 -47.5742)
				)
			)
		)
	)
	(footprint ""
		(layer "F.Cu")
		(at 5.9944 -39.318692 90)
		(property "Reference" "R124"
			(at 2.337308 0.08255 90)
			(unlocked yes)
			(layer "F.SilkS")
			(effects
				(font
					(size 0.635 0.4064)
					(thickness 0.1524)
				)
			)
		)
		(property "Value" "VAL*"
			(at 0.02032 2.13233 90)
			(unlocked yes)
			(layer "F.Fab")
			(hide yes)
			(effects
				(font
					(size 0.7874 0.5842)
					(thickness 0.1524)
				)
			)
		)
		(property "Device Type" "RESISTOR-G155-11000-01,100OHM,A"
			(at 0.008382 1.210564 90)
			(unlocked yes)
			(layer "F.Fab")
			(hide yes)
			(effects
				(font
					(size 0.7874 0.5842)
					(thickness 0.1524)
				)
			)
		)
		(property "User Part Number" "PARTNUM*"
			(at 0.02032 4.024884 90)
			(unlocked yes)
			(layer "Cmts.User")
			(hide yes)
			(effects
				(font
					(size 0.7874 0.5842)
					(thickness 0.1524)
				)
			)
		)
		(property "Tolerance" "TOL*"
			(at 0.044704 3.05435 90)
			(unlocked yes)
			(layer "Cmts.User")
			(hide yes)
			(effects
				(font
					(size 0.7874 0.5842)
					(thickness 0.1524)
				)
			)
		)
		(duplicate_pad_numbers_are_jumpers no)
		(fp_line
			(start 1.143 -0.5588)
			(end -1.143 -0.5588)
			(stroke
				(width 0.1)
				(type default)
			)
			(layer "F.SilkS")
		)
		(fp_line
			(start -1.143 -0.5588)
			(end -1.143 0.5588)
			(stroke
				(width 0.1)
				(type default)
			)
			(layer "F.SilkS")
		)
		(fp_line
			(start 1.143 0.5588)
			(end 1.143 -0.5588)
			(stroke
				(width 0.1)
				(type default)
			)
			(layer "F.SilkS")
		)
		(fp_line
			(start -1.143 0.5588)
			(end 1.143 0.5588)
			(stroke
				(width 0.1)
				(type default)
			)
			(layer "F.SilkS")
		)
		(fp_poly
			(pts
				(xy -1.143 0.5588) (xy 1.143 0.5588) (xy 1.143 -0.5588) (xy -1.143 -0.5588)
			)
			(stroke
				(width 0)
				(type default)
			)
			(fill no)
			(layer "F.CrtYd")
		)
		(fp_line
			(start 0.508 -0.3048)
			(end -0.508 -0.3048)
			(stroke
				(width 0.1)
				(type default)
			)
			(layer "F.Fab")
		)
		(fp_line
			(start -0.508 -0.3048)
			(end -0.508 0.3048)
			(stroke
				(width 0.1)
				(type default)
			)
			(layer "F.Fab")
		)
		(fp_line
			(start 0.508 0.3048)
			(end 0.508 -0.3048)
			(stroke
				(width 0.1)
				(type default)
			)
			(layer "F.Fab")
		)
		(fp_line
			(start -0.508 0.3048)
			(end 0.508 0.3048)
			(stroke
				(width 0.1)
				(type default)
			)
			(layer "F.Fab")
		)
		(pad "1" smd rect
			(at -0.5334 0 90)
			(size 0.7112 0.6096)
			(layers "F.Cu" "F.Mask" "F.Paste")
			(net "FPGA_OUT_SMA1_LED_BLUE_N")
		)
		(pad "2" smd rect
			(at 0.5334 0 90)
			(size 0.7112 0.6096)
			(layers "F.Cu" "F.Mask" "F.Paste")
			(net "UNNAMED_14_LED4PV14_I265_1")
		)
		(zone
			(layer "F.Cu")
			(hatch none 0.5)
			(connect_pads
				(clearance 0)
			)
			(min_thickness 0.25)
			(keepout
				(tracks not_allowed)
				(vias allowed)
				(pads allowed)
				(copperpour not_allowed)
				(footprints allowed)
			)
			(placement
				(enabled no)
				(sheetname "")
			)
			(fill
				(thermal_gap 0.5)
				(thermal_bridge_width 0.5)
				(island_removal_mode 0)
			)
			(polygon
				(pts
					(xy 6.2992 -39.242492) (xy 6.2992 -39.394892) (xy 5.6896 -39.394892) (xy 5.6896 -39.242492)
				)
			)
		)
		(zone
			(layer "F.Cu")
			(hatch none 0.5)
			(connect_pads
				(clearance 0)
			)
			(min_thickness 0.25)
			(keepout
				(tracks allowed)
				(vias not_allowed)
				(pads allowed)
				(copperpour not_allowed)
				(footprints allowed)
			)
			(placement
				(enabled no)
				(sheetname "")
			)
			(fill
				(thermal_gap 0.5)
				(thermal_bridge_width 0.5)
				(island_removal_mode 0)
			)
			(polygon
				(pts
					(xy 6.2992 -39.242492) (xy 6.2992 -39.394892) (xy 5.6896 -39.394892) (xy 5.6896 -39.242492)
				)
			)
		)
	)
)
